# BASEBOARD_FAB2 (Tioga Pass) — schematic netlist excerpt (pin names and nets, part order shuffled) for the footprints in the layout excerpt that follows; sources: Cadence DE-HDL packaged netlist, KiCad conversion of Wiwynn_Tioga_Pass_MB.brd

C2L20  CAP_A  0.01UF 25V 10% X7R  pkg 0402V  page 173 : A = SATA6G_PCH_PCIE_UP_SATA_RXP<4> ; B = SATA6G_P4_RX_C_DP

Q3U1  FET_N_DUAL  NTJD4001N FET  pkg SMLF  page 94
  SOURCE(0)  = GND
  GATE(0)  = IRQ_PVDDQ_ABC_VRHOT_LVT3_N
  DRAIN(0)  = H_CPU0_MEMABC_MEMHOT_G_N
  SOURCE(0)  = GND
  GATE(0)  = H_CPU0_MEMABC_MEMHOT
  DRAIN(0)  = H_CPU0_MEMABC_MEMHOT

(kicad_pcb
	(version 20260206)
	(generator "pcbnew")
	(generator_version "10.0")
	(general
		(thickness 1.6)
		(legacy_teardrops no)
	)
	(paper "A4")
	(title_block
		(title "Wiwynn_Tioga_Pass_MB.brd")
		(comment 1 "Tioga Pass / footprints 2423-2424 of 4770")
	)
	(layers
		(0 "F.Cu" signal "TOP")
		(4 "In1.Cu" signal "L2GND")
		(6 "In2.Cu" signal "L3")
		(8 "In3.Cu" signal "L4GND")
		(10 "In4.Cu" signal "L5")
		(12 "In5.Cu" signal "L6GND")
		(14 "In6.Cu" signal "L7VCC")
		(16 "In7.Cu" signal "L8VCC")
		(18 "In8.Cu" signal "L9GND")
		(20 "In9.Cu" signal "L10")
		(22 "In10.Cu" signal "L11GND")
		(24 "In11.Cu" signal "L12")
		(26 "In12.Cu" signal "L13GND")
		(2 "B.Cu" signal "BOTTOM")
		(9 "F.Adhes" user "F.Adhesive")
		(11 "B.Adhes" user "B.Adhesive")
		(13 "F.Paste" user "Package Geometry/Pastemask Top")
		(15 "B.Paste" user "Package Geometry/Pastemask Bottom")
		(5 "F.SilkS" user "Ref Des/Silkscreen Top")
		(7 "B.SilkS" user "Ref Des/Silkscreen Bottom")
		(1 "F.Mask" user "Board Geometry/Soldermask Top")
		(3 "B.Mask" user "Board Geometry/Soldermask Bottom")
		(17 "Dwgs.User" user "User.Drawings")
		(19 "Cmts.User" user "User.Comments")
		(21 "Eco1.User" user "User.Eco1")
		(23 "Eco2.User" user "User.Eco2")
		(25 "Edge.Cuts" user "Board Geometry/Outline")
		(27 "Margin" user)
		(31 "F.CrtYd" user "Package Geometry/Place Bound Top")
		(29 "B.CrtYd" user "Package Geometry/Place Bound Bottom")
		(35 "F.Fab" user "Ref Des/Assembly Top")
		(33 "B.Fab" user "Ref Des/Assembly Bottom")
	)
	(footprint ""
		(layer "B.Cu")
		(at 410.464 -149.06752 90)
		(property "Reference" "C2L20"
			(at 0 0 90)
			(layer "B.SilkS")
			(hide yes)
			(effects
				(font
					(size 1.27 1.27)
				)
				(justify mirror)
			)
		)
		(property "Value" ""
			(at 0 0 90)
			(layer "B.Fab")
			(effects
				(font
					(size 1.27 1.27)
				)
				(justify mirror)
			)
		)
		(duplicate_pad_numbers_are_jumpers no)
		(fp_poly
			(pts
				(xy -0.3048 -0.1016) (xy -0.3048 0.9906) (xy 0.3048 0.9906) (xy 0.3048 -0.1016)
			)
			(stroke
				(width 0)
				(type default)
			)
			(fill no)
			(layer "B.CrtYd")
		)
		(fp_line
			(start 0.3048 -0.1016)
			(end 0.3048 0.9906)
			(stroke
				(width 0.1)
				(type default)
			)
			(layer "B.Fab")
		)
		(fp_line
			(start -0.3048 -0.1016)
			(end 0.3048 -0.1016)
			(stroke
				(width 0.1)
				(type default)
			)
			(layer "B.Fab")
		)
		(fp_line
			(start 0.3048 0.9906)
			(end -0.3048 0.9906)
			(stroke
				(width 0.1)
				(type default)
			)
			(layer "B.Fab")
		)
		(fp_line
			(start -0.3048 0.9906)
			(end -0.3048 -0.1016)
			(stroke
				(width 0.1)
				(type default)
			)
			(layer "B.Fab")
		)
		(pad "1" smd rect
			(at 0 0 270)
			(size 0.508 0.508)
			(layers "B.Cu" "B.Mask" "B.Paste")
			(net "SATA6G_PCH_PCIE_UP_SATA_RXP<4>")
		)
		(pad "2" smd rect
			(at 0 0.889 270)
			(size 0.508 0.508)
			(layers "B.Cu" "B.Mask" "B.Paste")
			(net "SATA6G_P4_RX_C_DP")
		)
		(zone
			(layer "B.Cu")
			(hatch none 0.5)
			(connect_pads
				(clearance 0)
			)
			(min_thickness 0.25)
			(keepout
				(tracks allowed)
				(vias not_allowed)
				(pads allowed)
				(copperpour not_allowed)
				(footprints allowed)
			)
			(placement
				(enabled no)
				(sheetname "")
			)
			(fill
				(thermal_gap 0.5)
				(thermal_bridge_width 0.5)
				(island_removal_mode 0)
			)
			(polygon
				(pts
					(xy 410.718 -149.32152) (xy 410.718 -148.81352) (xy 411.099 -148.81352) (xy 411.099 -149.32152)
				)
			)
		)
		(zone
			(layer "B.Cu")
			(hatch none 0.5)
			(connect_pads
				(clearance 0)
			)
			(min_thickness 0.25)
			(keepout
				(tracks not_allowed)
				(vias allowed)
				(pads allowed)
				(copperpour not_allowed)
				(footprints allowed)
			)
			(placement
				(enabled no)
				(sheetname "")
			)
			(fill
				(thermal_gap 0.5)
				(thermal_bridge_width 0.5)
				(island_removal_mode 0)
			)
			(polygon
				(pts
					(xy 411.099 -149.32152) (xy 411.099 -148.81352) (xy 410.718 -148.81352) (xy 410.718 -149.32152)
				)
			)
		)
	)
	(footprint ""
		(layer "B.Cu")
		(at 409.884118 -92.860114 180)
		(property "Reference" "Q3U1"
			(at -2.737104 -0.459232 90)
			(unlocked yes)
			(layer "B.SilkS")
			(effects
				(font
					(size 0.7874 0.5842)
					(thickness 0.1524)
				)
				(justify left mirror)
			)
		)
		(property "Value" ""
			(at 0 0 0)
			(layer "B.Fab")
			(effects
				(font
					(size 1.27 1.27)
				)
				(justify mirror)
			)
		)
		(duplicate_pad_numbers_are_jumpers no)
		(fp_circle
			(center 0.508 -0.7874)
			(end 0.381 -0.7874)
			(stroke
				(width 0.254)
				(type default)
			)
			(fill no)
			(layer "B.SilkS")
		)
		(fp_poly
			(pts
				(xy -0.2159 1.7526) (xy -1.5621 1.7526) (xy -1.5621 -0.4572) (xy -0.2159 -0.4572)
			)
			(stroke
				(width 0)
				(type default)
			)
			(fill no)
			(layer "B.CrtYd")
		)
		(fp_line
			(start -0.2159 1.75514)
			(end -1.5621 1.75514)
			(stroke
				(width 0.1)
				(type default)
			)
			(layer "B.Fab")
		)
		(fp_line
			(start -0.2159 -0.45466)
			(end -0.2159 1.75514)
			(stroke
				(width 0.1)
				(type default)
			)
			(layer "B.Fab")
		)
		(fp_line
			(start -1.5621 1.75514)
			(end -1.5621 -0.45466)
			(stroke
				(width 0.1)
				(type default)
			)
			(layer "B.Fab")
		)
		(fp_line
			(start -1.5621 -0.45466)
			(end -0.2159 -0.45466)
			(stroke
				(width 0.1)
				(type default)
			)
			(layer "B.Fab")
		)
		(fp_circle
			(center 0.508 -0.7874)
			(end 0.381 -0.7874)
			(stroke
				(width 0.254)
				(type default)
			)
			(fill no)
			(layer "B.Fab")
		)
		(pad "1" smd rect
			(at 0 0)
			(size 1.016 0.381)
			(layers "B.Cu" "B.Mask" "B.Paste")
			(net "GND")
		)
		(pad "2" smd rect
			(at 0 0.65024)
			(size 1.016 0.381)
			(layers "B.Cu" "B.Mask" "B.Paste")
			(net "IRQ_PVDDQ_ABC_VRHOT_LVT3_N")
		)
		(pad "3" smd rect
			(at 0 1.30048)
			(size 1.016 0.381)
			(layers "B.Cu" "B.Mask" "B.Paste")
			(net "H_CPU0_MEMABC_MEMHOT_G_N")
		)
		(pad "4" smd rect
			(at -1.778 1.30048)
			(size 1.016 0.381)
			(layers "B.Cu" "B.Mask" "B.Paste")
			(net "GND")
		)
		(pad "5" smd rect
			(at -1.778 0.65024)
			(size 1.016 0.381)
			(layers "B.Cu" "B.Mask" "B.Paste")
			(net "H_CPU0_MEMABC_MEMHOT")
		)
		(pad "6" smd rect
			(at -1.778 0)
			(size 1.016 0.381)
			(layers "B.Cu" "B.Mask" "B.Paste")
			(net "H_CPU0_MEMABC_MEMHOT")
		)
		(zone
			(layer "B.Cu")
			(hatch none 0.5)
			(connect_pads
				(clearance 0)
			)
			(min_thickness 0.25)
			(keepout
				(tracks allowed)
				(vias not_allowed)
				(pads allowed)
				(copperpour not_allowed)
				(footprints allowed)
			)
			(placement
				(enabled no)
				(sheetname "")
			)
			(fill
				(thermal_gap 0.5)
				(thermal_bridge_width 0.5)
				(island_removal_mode 0)
			)
			(polygon
				(pts
					(xy 409.376118 -92.669614) (xy 410.392118 -92.669614) (xy 410.392118 -94.358714) (xy 409.376118 -94.358714)
				)
			)
		)
		(zone
			(layer "B.Cu")
			(hatch none 0.5)
			(connect_pads
				(clearance 0)
			)
			(min_thickness 0.25)
			(keepout
				(tracks allowed)
				(vias not_allowed)
				(pads allowed)
				(copperpour not_allowed)
				(footprints allowed)
			)
			(placement
				(enabled no)
				(sheetname "")
			)
			(fill
				(thermal_gap 0.5)
				(thermal_bridge_width 0.5)
				(island_removal_mode 0)
			)
			(polygon
				(pts
					(xy 411.154118 -92.669614) (xy 412.170118 -92.669614) (xy 412.170118 -94.358714) (xy 411.154118 -94.358714)
				)
			)
		)
	)
)
